# BASEBOARD_FAB2 (Tioga Pass) — schematic netlist excerpt (pin names and nets, part order shuffled) for the footprints in the layout excerpt that follows; sources: Cadence DE-HDL packaged netlist, KiCad conversion of Wiwynn_Tioga_Pass_MB.brd

C22W15  SC22U16V5MX-4-GP  20%  pkg SMD-BCG5  page 214 : \1\ = VR_FET_SW_P12V_STBY_PVCCIN_CPU0 ; \2\ = GND
R25W75  RES  33.2 1% CHIP  pkg 0402  page 144 : A = FM_CPU1_FIVR_FAULT_LVT3_R_N ; B = FM_CPU1_FIVR_FAULT_LVT3_N
C9U11  CAP  10UF 16V 10% X7R  pkg 0805  page 197 : A = P12V_NVDIMM_GHJ ; B = GND

(kicad_pcb
	(version 20260206)
	(generator "pcbnew")
	(generator_version "10.0")
	(general
		(thickness 1.6)
		(legacy_teardrops no)
	)
	(paper "A4")
	(title_block
		(title "Wiwynn_Tioga_Pass_MB.brd")
		(comment 1 "Tioga Pass / footprints 2688-2690 of 4770")
	)
	(layers
		(0 "F.Cu" signal "TOP")
		(4 "In1.Cu" signal "L2GND")
		(6 "In2.Cu" signal "L3")
		(8 "In3.Cu" signal "L4GND")
		(10 "In4.Cu" signal "L5")
		(12 "In5.Cu" signal "L6GND")
		(14 "In6.Cu" signal "L7VCC")
		(16 "In7.Cu" signal "L8VCC")
		(18 "In8.Cu" signal "L9GND")
		(20 "In9.Cu" signal "L10")
		(22 "In10.Cu" signal "L11GND")
		(24 "In11.Cu" signal "L12")
		(26 "In12.Cu" signal "L13GND")
		(2 "B.Cu" signal "BOTTOM")
		(9 "F.Adhes" user "F.Adhesive")
		(11 "B.Adhes" user "B.Adhesive")
		(13 "F.Paste" user "Package Geometry/Pastemask Top")
		(15 "B.Paste" user "Package Geometry/Pastemask Bottom")
		(5 "F.SilkS" user "Ref Des/Silkscreen Top")
		(7 "B.SilkS" user "Ref Des/Silkscreen Bottom")
		(1 "F.Mask" user "Board Geometry/Soldermask Top")
		(3 "B.Mask" user "Board Geometry/Soldermask Bottom")
		(17 "Dwgs.User" user "User.Drawings")
		(19 "Cmts.User" user "User.Comments")
		(21 "Eco1.User" user "User.Eco1")
		(23 "Eco2.User" user "User.Eco2")
		(25 "Edge.Cuts" user "Board Geometry/Outline")
		(27 "Margin" user)
		(31 "F.CrtYd" user "Package Geometry/Place Bound Top")
		(29 "B.CrtYd" user "Package Geometry/Place Bound Bottom")
		(35 "F.Fab" user "Ref Des/Assembly Top")
		(33 "B.Fab" user "Ref Des/Assembly Bottom")
	)
	(footprint ""
		(layer "B.Cu")
		(at 28.0924 2.1336 -90)
		(property "Reference" "C9U11"
			(at 0 0 90)
			(layer "B.SilkS")
			(hide yes)
			(effects
				(font
					(size 1.27 1.27)
				)
				(justify mirror)
			)
		)
		(property "Value" ""
			(at 0 0 90)
			(layer "B.Fab")
			(effects
				(font
					(size 1.27 1.27)
				)
				(justify mirror)
			)
		)
		(duplicate_pad_numbers_are_jumpers no)
		(fp_rect
			(start 0.7239 -0.2159)
			(end -0.7239 1.9939)
			(stroke
				(width 0)
				(type default)
			)
			(fill no)
			(layer "B.CrtYd")
		)
		(fp_line
			(start -0.7239 1.9939)
			(end -0.7239 -0.2159)
			(stroke
				(width 0.1)
				(type default)
			)
			(layer "B.Fab")
		)
		(fp_line
			(start 0.7239 1.9939)
			(end -0.7239 1.9939)
			(stroke
				(width 0.1)
				(type default)
			)
			(layer "B.Fab")
		)
		(fp_line
			(start -0.7239 -0.2159)
			(end 0.7239 -0.2159)
			(stroke
				(width 0.1)
				(type default)
			)
			(layer "B.Fab")
		)
		(fp_line
			(start 0.7239 -0.2159)
			(end 0.7239 1.9939)
			(stroke
				(width 0.1)
				(type default)
			)
			(layer "B.Fab")
		)
		(pad "1" smd rect
			(at 0 0 90)
			(size 1.27 1.016)
			(layers "B.Cu" "B.Mask" "B.Paste")
			(net "P12V_NVDIMM_GHJ")
		)
		(pad "2" smd rect
			(at 0 1.778 90)
			(size 1.27 1.016)
			(layers "B.Cu" "B.Mask" "B.Paste")
			(net "GND")
		)
		(zone
			(layer "B.Cu")
			(hatch none 0.5)
			(connect_pads
				(clearance 0)
			)
			(min_thickness 0.25)
			(keepout
				(tracks not_allowed)
				(vias allowed)
				(pads allowed)
				(copperpour not_allowed)
				(footprints allowed)
			)
			(placement
				(enabled no)
				(sheetname "")
			)
			(fill
				(thermal_gap 0.5)
				(thermal_bridge_width 0.5)
				(island_removal_mode 0)
			)
			(polygon
				(pts
					(xy 27.5844 2.7686) (xy 27.5844 1.4986) (xy 26.8224 1.4986) (xy 26.8224 2.7686)
				)
			)
		)
	)
	(footprint ""
		(layer "B.Cu")
		(at 402.3995 -42.164 -90)
		(property "Reference" "R25W75"
			(at 0.8382 -0.67818 270)
			(unlocked yes)
			(layer "B.SilkS")
			(effects
				(font
					(size 0.4064 0.254)
					(thickness 0.1524)
				)
				(justify left mirror)
			)
		)
		(property "Value" ""
			(at 0 0 90)
			(layer "B.Fab")
			(effects
				(font
					(size 1.27 1.27)
				)
				(justify mirror)
			)
		)
		(duplicate_pad_numbers_are_jumpers no)
		(fp_poly
			(pts
				(xy 0.2794 -0.1016) (xy -0.2794 -0.1016) (xy -0.2794 0.9906) (xy 0.2794 0.9906)
			)
			(stroke
				(width 0)
				(type default)
			)
			(fill no)
			(layer "B.CrtYd")
		)
		(fp_line
			(start -0.2794 0.9906)
			(end -0.2794 -0.1016)
			(stroke
				(width 0.1)
				(type default)
			)
			(layer "B.Fab")
		)
		(fp_line
			(start 0.2794 0.9906)
			(end -0.2794 0.9906)
			(stroke
				(width 0.1)
				(type default)
			)
			(layer "B.Fab")
		)
		(fp_line
			(start -0.2794 -0.1016)
			(end 0.2794 -0.1016)
			(stroke
				(width 0.1)
				(type default)
			)
			(layer "B.Fab")
		)
		(fp_line
			(start 0.2794 -0.1016)
			(end 0.2794 0.9906)
			(stroke
				(width 0.1)
				(type default)
			)
			(layer "B.Fab")
		)
		(pad "1" smd rect
			(at 0 0 90)
			(size 0.508 0.508)
			(layers "B.Cu" "B.Mask" "B.Paste")
			(net "FM_CPU1_FIVR_FAULT_LVT3_R_N")
		)
		(pad "2" smd rect
			(at 0 0.889 90)
			(size 0.508 0.508)
			(layers "B.Cu" "B.Mask" "B.Paste")
			(net "FM_CPU1_FIVR_FAULT_LVT3_N")
		)
		(zone
			(layer "B.Cu")
			(hatch none 0.5)
			(connect_pads
				(clearance 0)
			)
			(min_thickness 0.25)
			(keepout
				(tracks not_allowed)
				(vias allowed)
				(pads allowed)
				(copperpour not_allowed)
				(footprints allowed)
			)
			(placement
				(enabled no)
				(sheetname "")
			)
			(fill
				(thermal_gap 0.5)
				(thermal_bridge_width 0.5)
				(island_removal_mode 0)
			)
			(polygon
				(pts
					(xy 401.7645 -41.91) (xy 401.7645 -42.418) (xy 402.1455 -42.418) (xy 402.1455 -41.91)
				)
			)
		)
		(zone
			(layer "B.Cu")
			(hatch none 0.5)
			(connect_pads
				(clearance 0)
			)
			(min_thickness 0.25)
			(keepout
				(tracks allowed)
				(vias not_allowed)
				(pads allowed)
				(copperpour not_allowed)
				(footprints allowed)
			)
			(placement
				(enabled no)
				(sheetname "")
			)
			(fill
				(thermal_gap 0.5)
				(thermal_bridge_width 0.5)
				(island_removal_mode 0)
			)
			(polygon
				(pts
					(xy 402.1455 -41.91) (xy 402.1455 -42.418) (xy 401.7645 -42.418) (xy 401.7645 -41.91)
				)
			)
		)
	)
	(footprint ""
		(layer "B.Cu")
		(at 186.015376 -59.243722 180)
		(property "Reference" "C22W15"
			(at 0 0 0)
			(layer "B.SilkS")
			(hide yes)
			(effects
				(font
					(size 1.27 1.27)
				)
				(justify mirror)
			)
		)
		(property "Value" "*"
			(at 0.0762 -6.2357 180)
			(unlocked yes)
			(layer "B.Fab")
			(hide yes)
			(effects
				(font
					(size 1.27 1.016)
					(thickness 0.1524)
				)
				(justify mirror)
			)
		)
		(property "Device Type" "SC22U16V5MX-4-GP_SMD-BCG5-SC22A"
			(at 0.0762 -8.2677 180)
			(unlocked yes)
			(layer "B.Fab")
			(hide yes)
			(effects
				(font
					(size 1.27 1.016)
					(thickness 0.1524)
				)
				(justify mirror)
			)
		)
		(duplicate_pad_numbers_are_jumpers no)
		(fp_line
			(start -0.635 0)
			(end 0.635 0)
			(stroke
				(width 0.508)
				(type default)
			)
			(layer "B.SilkS")
		)
		(fp_rect
			(start 0.9652 1.778)
			(end -0.9652 -1.778)
			(stroke
				(width 0)
				(type default)
			)
			(fill no)
			(layer "B.CrtYd")
		)
		(fp_poly
			(pts
				(xy 0.9652 -1.778) (xy -0.9652 -1.778) (xy -0.9652 1.778) (xy 0.9652 1.778)
			)
			(stroke
				(width 0)
				(type default)
			)
			(fill no)
			(layer "B.Fab")
		)
		(pad "1" smd rect
			(at 0 -0.9652)
			(size 1.397 1.143)
			(layers "B.Cu" "B.Mask" "B.Paste")
			(net "VR_FET_SW_P12V_STBY_PVCCIN_CPU0")
		)
		(pad "2" smd rect
			(at 0 0.9652)
			(size 1.397 1.143)
			(layers "B.Cu" "B.Mask" "B.Paste")
			(net "GND")
		)
	)
)
